(kicad_pcb
	(version 20260206)
	(generator "pcbnew")
	(generator_version "10.0")
	(general
		(thickness 1.6)
		(legacy_teardrops no)
	)
	(paper "A4")
	(title_block
		(title "03242023_DA0F0TMBIJ0_F0T_Motherboard_J_brd_V01_OCP.brd")
		(comment 1 "Grand Teton / footprints 4427-4433 of 6105")
	)
	(layers
		(0 "F.Cu" signal "TOP")
		(4 "In1.Cu" signal "GND")
		(6 "In2.Cu" signal "IN1")
		(8 "In3.Cu" signal "GND1")
		(10 "In4.Cu" signal "IN2")
		(12 "In5.Cu" signal "GND2")
		(14 "In6.Cu" signal "IN3")
		(16 "In7.Cu" signal "GND3")
		(18 "In8.Cu" signal "VCC")
		(20 "In9.Cu" signal "VCC1")
		(22 "In10.Cu" signal "GND4")
		(24 "In11.Cu" signal "IN4")
		(26 "In12.Cu" signal "GND5")
		(28 "In13.Cu" signal "IN5")
		(30 "In14.Cu" signal "GND6")
		(32 "In15.Cu" signal "IN6")
		(34 "In16.Cu" signal "GND7")
		(2 "B.Cu" signal "BOTTOM")
		(9 "F.Adhes" user "F.Adhesive")
		(11 "B.Adhes" user "B.Adhesive")
		(13 "F.Paste" user "Package Geometry/Pastemask Top")
		(15 "B.Paste" user "Package Geometry/Pastemask Bottom")
		(5 "F.SilkS" user "Ref Des/Silkscreen Top")
		(7 "B.SilkS" user "Ref Des/Silkscreen Bottom")
		(1 "F.Mask" user "Board Geometry/Soldermask Top")
		(3 "B.Mask" user "Board Geometry/Soldermask Bottom")
		(17 "Dwgs.User" user "User.Drawings")
		(19 "Cmts.User" user "User.Comments")
		(21 "Eco1.User" user "User.Eco1")
		(23 "Eco2.User" user "User.Eco2")
		(25 "Edge.Cuts" user "Board Geometry/Outline")
		(27 "Margin" user)
		(31 "F.CrtYd" user "Package Geometry/Place Bound Top")
		(29 "B.CrtYd" user "Package Geometry/Place Bound Bottom")
		(35 "F.Fab" user "Ref Des/Assembly Top")
		(33 "B.Fab" user "Ref Des/Assembly Bottom")
	)
	(footprint ""
		(layer "B.Cu")
		(at 195.253356 -423.657014 -90)
		(property "Reference" "R4707"
			(at 0 0 90)
			(layer "B.SilkS")
			(hide yes)
			(effects
				(font
					(size 1.27 1.27)
				)
				(justify mirror)
			)
		)
		(property "Value" ""
			(at 0 0 90)
			(layer "B.Fab")
			(effects
				(font
					(size 1.27 1.27)
				)
				(justify mirror)
			)
		)
		(duplicate_pad_numbers_are_jumpers no)
		(fp_line
			(start -0.7874 0.4064)
			(end 0.7874 0.4064)
			(stroke
				(width 0.1524)
				(type default)
			)
			(layer "B.SilkS")
		)
		(fp_line
			(start 0.7874 0.4064)
			(end 0.7874 -0.4064)
			(stroke
				(width 0.1524)
				(type default)
			)
			(layer "B.SilkS")
		)
		(fp_line
			(start -0.7874 -0.4064)
			(end -0.7874 0.4064)
			(stroke
				(width 0.1524)
				(type default)
			)
			(layer "B.SilkS")
		)
		(fp_line
			(start 0.7874 -0.4064)
			(end -0.7874 -0.4064)
			(stroke
				(width 0.1524)
				(type default)
			)
			(layer "B.SilkS")
		)
		(fp_line
			(start -0.67945 0.3048)
			(end -0.120396 0.3048)
			(stroke
				(width 0.1)
				(type default)
			)
			(layer "B.Fab")
		)
		(fp_line
			(start -0.120396 0.3048)
			(end -0.120396 0.2794)
			(stroke
				(width 0.1)
				(type default)
			)
			(layer "B.Fab")
		)
		(fp_line
			(start 0.12065 0.3048)
			(end 0.67945 0.3048)
			(stroke
				(width 0.1)
				(type default)
			)
			(layer "B.Fab")
		)
		(fp_line
			(start 0.67945 0.3048)
			(end 0.67945 -0.305054)
			(stroke
				(width 0.1)
				(type default)
			)
			(layer "B.Fab")
		)
		(fp_line
			(start -0.120396 0.2794)
			(end 0.12065 0.2794)
			(stroke
				(width 0.1)
				(type default)
			)
			(layer "B.Fab")
		)
		(fp_line
			(start 0.12065 0.2794)
			(end 0.12065 0.3048)
			(stroke
				(width 0.1)
				(type default)
			)
			(layer "B.Fab")
		)
		(fp_line
			(start -0.12065 -0.2794)
			(end -0.12065 -0.3048)
			(stroke
				(width 0.1)
				(type default)
			)
			(layer "B.Fab")
		)
		(fp_line
			(start 0.12065 -0.2794)
			(end -0.12065 -0.2794)
			(stroke
				(width 0.1)
				(type default)
			)
			(layer "B.Fab")
		)
		(fp_line
			(start -0.67945 -0.3048)
			(end -0.67945 0.3048)
			(stroke
				(width 0.1)
				(type default)
			)
			(layer "B.Fab")
		)
		(fp_line
			(start -0.12065 -0.3048)
			(end -0.67945 -0.3048)
			(stroke
				(width 0.1)
				(type default)
			)
			(layer "B.Fab")
		)
		(fp_line
			(start 0.12065 -0.305054)
			(end 0.12065 -0.2794)
			(stroke
				(width 0.1)
				(type default)
			)
			(layer "B.Fab")
		)
		(fp_line
			(start 0.67945 -0.305054)
			(end 0.12065 -0.305054)
			(stroke
				(width 0.1)
				(type default)
			)
			(layer "B.Fab")
		)
		(pad "1" smd circle
			(at 0.40005 0 90)
			(size 0 0)
			(layers "B.Cu" "B.Mask" "B.Paste")
			(net "LED_P12V_PSU_R3")
		)
		(pad "2" smd circle
			(at -0.40005 0 90)
			(size 0 0)
			(layers "B.Cu" "B.Mask" "B.Paste")
			(net "P12V_PSU")
		)
	)
	(footprint ""
		(layer "B.Cu")
		(at 78.223618 -184.110376 90)
		(property "Reference" "R341"
			(at 0 0 90)
			(layer "B.SilkS")
			(hide yes)
			(effects
				(font
					(size 1.27 1.27)
				)
				(justify mirror)
			)
		)
		(property "Value" ""
			(at 0 0 90)
			(layer "B.Fab")
			(effects
				(font
					(size 1.27 1.27)
				)
				(justify mirror)
			)
		)
		(duplicate_pad_numbers_are_jumpers no)
		(fp_line
			(start 0.7874 -0.4064)
			(end -0.7874 -0.4064)
			(stroke
				(width 0.1524)
				(type default)
			)
			(layer "B.SilkS")
		)
		(fp_line
			(start -0.7874 -0.4064)
			(end -0.7874 0.4064)
			(stroke
				(width 0.1524)
				(type default)
			)
			(layer "B.SilkS")
		)
		(fp_line
			(start 0.7874 0.4064)
			(end 0.7874 -0.4064)
			(stroke
				(width 0.1524)
				(type default)
			)
			(layer "B.SilkS")
		)
		(fp_line
			(start -0.7874 0.4064)
			(end 0.7874 0.4064)
			(stroke
				(width 0.1524)
				(type default)
			)
			(layer "B.SilkS")
		)
		(fp_line
			(start 0.67945 -0.305054)
			(end 0.12065 -0.305054)
			(stroke
				(width 0.1)
				(type default)
			)
			(layer "B.Fab")
		)
		(fp_line
			(start 0.12065 -0.305054)
			(end 0.12065 -0.2794)
			(stroke
				(width 0.1)
				(type default)
			)
			(layer "B.Fab")
		)
		(fp_line
			(start -0.12065 -0.3048)
			(end -0.67945 -0.3048)
			(stroke
				(width 0.1)
				(type default)
			)
			(layer "B.Fab")
		)
		(fp_line
			(start -0.67945 -0.3048)
			(end -0.67945 0.3048)
			(stroke
				(width 0.1)
				(type default)
			)
			(layer "B.Fab")
		)
		(fp_line
			(start 0.12065 -0.2794)
			(end -0.12065 -0.2794)
			(stroke
				(width 0.1)
				(type default)
			)
			(layer "B.Fab")
		)
		(fp_line
			(start -0.12065 -0.2794)
			(end -0.12065 -0.3048)
			(stroke
				(width 0.1)
				(type default)
			)
			(layer "B.Fab")
		)
		(fp_line
			(start 0.12065 0.2794)
			(end 0.12065 0.3048)
			(stroke
				(width 0.1)
				(type default)
			)
			(layer "B.Fab")
		)
		(fp_line
			(start -0.120396 0.2794)
			(end 0.12065 0.2794)
			(stroke
				(width 0.1)
				(type default)
			)
			(layer "B.Fab")
		)
		(fp_line
			(start 0.67945 0.3048)
			(end 0.67945 -0.305054)
			(stroke
				(width 0.1)
				(type default)
			)
			(layer "B.Fab")
		)
		(fp_line
			(start 0.12065 0.3048)
			(end 0.67945 0.3048)
			(stroke
				(width 0.1)
				(type default)
			)
			(layer "B.Fab")
		)
		(fp_line
			(start -0.120396 0.3048)
			(end -0.120396 0.2794)
			(stroke
				(width 0.1)
				(type default)
			)
			(layer "B.Fab")
		)
		(fp_line
			(start -0.67945 0.3048)
			(end -0.120396 0.3048)
			(stroke
				(width 0.1)
				(type default)
			)
			(layer "B.Fab")
		)
		(pad "1" smd circle
			(at 0.40005 0 270)
			(size 0 0)
			(layers "B.Cu" "B.Mask" "B.Paste")
			(net "H_CPU1_ERR1_LVC1_R_N")
		)
		(pad "2" smd circle
			(at -0.40005 0 270)
			(size 0 0)
			(layers "B.Cu" "B.Mask" "B.Paste")
			(net "H_CPU_ERR1_LVC1_R_N")
		)
	)
	(footprint ""
		(layer "B.Cu")
		(at 376.518932 -80.354424 180)
		(property "Reference" "PC1237"
			(at 0 0 0)
			(layer "B.SilkS")
			(hide yes)
			(effects
				(font
					(size 1.27 1.27)
				)
				(justify mirror)
			)
		)
		(property "Value" ""
			(at 0 0 0)
			(layer "B.Fab")
			(effects
				(font
					(size 1.27 1.27)
				)
				(justify mirror)
			)
		)
		(duplicate_pad_numbers_are_jumpers no)
		(fp_line
			(start 1.524 0.762)
			(end 1.524 -0.762)
			(stroke
				(width 0.1524)
				(type default)
			)
			(layer "B.SilkS")
		)
		(fp_line
			(start 1.524 -0.762)
			(end -1.524 -0.762)
			(stroke
				(width 0.1524)
				(type default)
			)
			(layer "B.SilkS")
		)
		(fp_line
			(start -1.524 0.762)
			(end 1.524 0.762)
			(stroke
				(width 0.1524)
				(type default)
			)
			(layer "B.SilkS")
		)
		(fp_line
			(start -1.524 -0.762)
			(end -1.524 0.762)
			(stroke
				(width 0.1524)
				(type default)
			)
			(layer "B.SilkS")
		)
		(fp_line
			(start 1.1049 0.724916)
			(end -1.1049 0.724916)
			(stroke
				(width 0.1)
				(type default)
			)
			(layer "B.Fab")
		)
		(fp_line
			(start 1.1049 -0.724916)
			(end 1.1049 0.724916)
			(stroke
				(width 0.1)
				(type default)
			)
			(layer "B.Fab")
		)
		(fp_line
			(start -1.1049 0.724916)
			(end -1.1049 -0.724916)
			(stroke
				(width 0.1)
				(type default)
			)
			(layer "B.Fab")
		)
		(fp_line
			(start -1.1049 -0.724916)
			(end 1.1049 -0.724916)
			(stroke
				(width 0.1)
				(type default)
			)
			(layer "B.Fab")
		)
		(pad "1" smd rect
			(at 0.889 0 180)
			(size 1.016 1.27)
			(layers "B.Cu" "B.Mask" "B.Paste")
			(net "P1V8_PCH_AUX")
		)
		(pad "2" smd rect
			(at -0.889 0 180)
			(size 1.016 1.27)
			(layers "B.Cu" "B.Mask" "B.Paste")
			(net "GND")
		)
	)
	(footprint ""
		(layer "B.Cu")
		(at 51.714908 -193.25971 -90)
		(property "Reference" "R260"
			(at 0 0 90)
			(layer "B.SilkS")
			(hide yes)
			(effects
				(font
					(size 1.27 1.27)
				)
				(justify mirror)
			)
		)
		(property "Value" ""
			(at 0 0 90)
			(layer "B.Fab")
			(effects
				(font
					(size 1.27 1.27)
				)
				(justify mirror)
			)
		)
		(duplicate_pad_numbers_are_jumpers no)
		(fp_line
			(start -0.7874 0.4064)
			(end 0.7874 0.4064)
			(stroke
				(width 0.1524)
				(type default)
			)
			(layer "B.SilkS")
		)
		(fp_line
			(start 0.7874 0.4064)
			(end 0.7874 -0.4064)
			(stroke
				(width 0.1524)
				(type default)
			)
			(layer "B.SilkS")
		)
		(fp_line
			(start -0.7874 -0.4064)
			(end -0.7874 0.4064)
			(stroke
				(width 0.1524)
				(type default)
			)
			(layer "B.SilkS")
		)
		(fp_line
			(start 0.7874 -0.4064)
			(end -0.7874 -0.4064)
			(stroke
				(width 0.1524)
				(type default)
			)
			(layer "B.SilkS")
		)
		(fp_line
			(start -0.67945 0.3048)
			(end -0.120396 0.3048)
			(stroke
				(width 0.1)
				(type default)
			)
			(layer "B.Fab")
		)
		(fp_line
			(start -0.120396 0.3048)
			(end -0.120396 0.2794)
			(stroke
				(width 0.1)
				(type default)
			)
			(layer "B.Fab")
		)
		(fp_line
			(start 0.12065 0.3048)
			(end 0.67945 0.3048)
			(stroke
				(width 0.1)
				(type default)
			)
			(layer "B.Fab")
		)
		(fp_line
			(start 0.67945 0.3048)
			(end 0.67945 -0.305054)
			(stroke
				(width 0.1)
				(type default)
			)
			(layer "B.Fab")
		)
		(fp_line
			(start -0.120396 0.2794)
			(end 0.12065 0.2794)
			(stroke
				(width 0.1)
				(type default)
			)
			(layer "B.Fab")
		)
		(fp_line
			(start 0.12065 0.2794)
			(end 0.12065 0.3048)
			(stroke
				(width 0.1)
				(type default)
			)
			(layer "B.Fab")
		)
		(fp_line
			(start -0.12065 -0.2794)
			(end -0.12065 -0.3048)
			(stroke
				(width 0.1)
				(type default)
			)
			(layer "B.Fab")
		)
		(fp_line
			(start 0.12065 -0.2794)
			(end -0.12065 -0.2794)
			(stroke
				(width 0.1)
				(type default)
			)
			(layer "B.Fab")
		)
		(fp_line
			(start -0.67945 -0.3048)
			(end -0.67945 0.3048)
			(stroke
				(width 0.1)
				(type default)
			)
			(layer "B.Fab")
		)
		(fp_line
			(start -0.12065 -0.3048)
			(end -0.67945 -0.3048)
			(stroke
				(width 0.1)
				(type default)
			)
			(layer "B.Fab")
		)
		(fp_line
			(start 0.12065 -0.305054)
			(end 0.12065 -0.2794)
			(stroke
				(width 0.1)
				(type default)
			)
			(layer "B.Fab")
		)
		(fp_line
			(start 0.67945 -0.305054)
			(end 0.12065 -0.305054)
			(stroke
				(width 0.1)
				(type default)
			)
			(layer "B.Fab")
		)
		(pad "1" smd circle
			(at 0.40005 0 90)
			(size 0 0)
			(layers "B.Cu" "B.Mask" "B.Paste")
			(net "PVNN_TERM_CPU1")
		)
		(pad "2" smd circle
			(at -0.40005 0 90)
			(size 0 0)
			(layers "B.Cu" "B.Mask" "B.Paste")
			(net "FM_S3M_CPU1_LVC1_GPIO_3")
		)
	)
	(footprint ""
		(layer "B.Cu")
		(at 155.031694 -36.950142 180)
		(property "Reference" "C2322"
			(at 0 0 0)
			(layer "B.SilkS")
			(hide yes)
			(effects
				(font
					(size 1.27 1.27)
				)
				(justify mirror)
			)
		)
		(property "Value" ""
			(at 0 0 0)
			(layer "B.Fab")
			(effects
				(font
					(size 1.27 1.27)
				)
				(justify mirror)
			)
		)
		(duplicate_pad_numbers_are_jumpers no)
		(fp_line
			(start 0.7874 0.4064)
			(end 0.7874 -0.4064)
			(stroke
				(width 0.1524)
				(type default)
			)
			(layer "B.SilkS")
		)
		(fp_line
			(start 0.7874 -0.4064)
			(end -0.7874 -0.4064)
			(stroke
				(width 0.1524)
				(type default)
			)
			(layer "B.SilkS")
		)
		(fp_line
			(start -0.7874 0.4064)
			(end 0.7874 0.4064)
			(stroke
				(width 0.1524)
				(type default)
			)
			(layer "B.SilkS")
		)
		(fp_line
			(start -0.7874 -0.4064)
			(end -0.7874 0.4064)
			(stroke
				(width 0.1524)
				(type default)
			)
			(layer "B.SilkS")
		)
		(fp_line
			(start 0.67945 0.3048)
			(end 0.67945 -0.305054)
			(stroke
				(width 0.1)
				(type default)
			)
			(layer "B.Fab")
		)
		(fp_line
			(start 0.67945 -0.305054)
			(end 0.12065 -0.305054)
			(stroke
				(width 0.1)
				(type default)
			)
			(layer "B.Fab")
		)
		(fp_line
			(start 0.12065 0.3048)
			(end 0.67945 0.3048)
			(stroke
				(width 0.1)
				(type default)
			)
			(layer "B.Fab")
		)
		(fp_line
			(start 0.12065 0.2794)
			(end 0.12065 0.3048)
			(stroke
				(width 0.1)
				(type default)
			)
			(layer "B.Fab")
		)
		(fp_line
			(start 0.12065 -0.2794)
			(end -0.12065 -0.2794)
			(stroke
				(width 0.1)
				(type default)
			)
			(layer "B.Fab")
		)
		(fp_line
			(start 0.12065 -0.305054)
			(end 0.12065 -0.2794)
			(stroke
				(width 0.1)
				(type default)
			)
			(layer "B.Fab")
		)
		(fp_line
			(start -0.120396 0.3048)
			(end -0.120396 0.2794)
			(stroke
				(width 0.1)
				(type default)
			)
			(layer "B.Fab")
		)
		(fp_line
			(start -0.120396 0.2794)
			(end 0.12065 0.2794)
			(stroke
				(width 0.1)
				(type default)
			)
			(layer "B.Fab")
		)
		(fp_line
			(start -0.12065 -0.2794)
			(end -0.12065 -0.3048)
			(stroke
				(width 0.1)
				(type default)
			)
			(layer "B.Fab")
		)
		(fp_line
			(start -0.12065 -0.3048)
			(end -0.67945 -0.3048)
			(stroke
				(width 0.1)
				(type default)
			)
			(layer "B.Fab")
		)
		(fp_line
			(start -0.67945 0.3048)
			(end -0.120396 0.3048)
			(stroke
				(width 0.1)
				(type default)
			)
			(layer "B.Fab")
		)
		(fp_line
			(start -0.67945 -0.3048)
			(end -0.67945 0.3048)
			(stroke
				(width 0.1)
				(type default)
			)
			(layer "B.Fab")
		)
		(pad "1" smd circle
			(at 0.40005 0)
			(size 0 0)
			(layers "B.Cu" "B.Mask" "B.Paste")
			(net "P3V3_AUX_USB_HUB_2")
		)
		(pad "2" smd circle
			(at -0.40005 0)
			(size 0 0)
			(layers "B.Cu" "B.Mask" "B.Paste")
			(net "GND")
		)
	)
	(footprint ""
		(layer "B.Cu")
		(at 337.218782 -64.315848 90)
		(property "Reference" "C169"
			(at 0 0 90)
			(layer "B.SilkS")
			(hide yes)
			(effects
				(font
					(size 1.27 1.27)
				)
				(justify mirror)
			)
		)
		(property "Value" ""
			(at 0 0 90)
			(layer "B.Fab")
			(effects
				(font
					(size 1.27 1.27)
				)
				(justify mirror)
			)
		)
		(duplicate_pad_numbers_are_jumpers no)
		(fp_line
			(start 0.299974 -0.150114)
			(end -0.299974 -0.150114)
			(stroke
				(width 0.1)
				(type default)
			)
			(layer "B.Fab")
		)
		(fp_line
			(start -0.299974 -0.150114)
			(end -0.299974 0.150114)
			(stroke
				(width 0.1)
				(type default)
			)
			(layer "B.Fab")
		)
		(fp_line
			(start 0.299974 0.150114)
			(end 0.299974 -0.150114)
			(stroke
				(width 0.1)
				(type default)
			)
			(layer "B.Fab")
		)
		(fp_line
			(start -0.299974 0.150114)
			(end 0.299974 0.150114)
			(stroke
				(width 0.1)
				(type default)
			)
			(layer "B.Fab")
		)
		(pad "1" smd rect
			(at 0.2667 0 270)
			(size 0.3048 0.381)
			(layers "B.Cu" "B.Mask" "B.Paste")
			(net "DMI_CPU0_PCH_RX_C_DN<0>")
		)
		(pad "2" smd rect
			(at -0.2667 0 270)
			(size 0.3048 0.381)
			(layers "B.Cu" "B.Mask" "B.Paste")
			(net "DMI_CPU0_PCH_RX_DN<0>")
		)
	)
	(footprint ""
		(layer "B.Cu")
		(at 341.272114 -31.678372)
		(property "Reference" "R8"
			(at 0 0 0)
			(layer "B.SilkS")
			(hide yes)
			(effects
				(font
					(size 1.27 1.27)
				)
				(justify mirror)
			)
		)
		(property "Value" ""
			(at 0 0 0)
			(layer "B.Fab")
			(effects
				(font
					(size 1.27 1.27)
				)
				(justify mirror)
			)
		)
		(duplicate_pad_numbers_are_jumpers no)
		(fp_line
			(start -0.7874 -0.4064)
			(end -0.7874 0.4064)
			(stroke
				(width 0.1524)
				(type default)
			)
			(layer "B.SilkS")
		)
		(fp_line
			(start -0.7874 0.4064)
			(end 0.7874 0.4064)
			(stroke
				(width 0.1524)
				(type default)
			)
			(layer "B.SilkS")
		)
		(fp_line
			(start 0.7874 -0.4064)
			(end -0.7874 -0.4064)
			(stroke
				(width 0.1524)
				(type default)
			)
			(layer "B.SilkS")
		)
		(fp_line
			(start 0.7874 0.4064)
			(end 0.7874 -0.4064)
			(stroke
				(width 0.1524)
				(type default)
			)
			(layer "B.SilkS")
		)
		(fp_line
			(start -0.67945 -0.3048)
			(end -0.67945 0.3048)
			(stroke
				(width 0.1)
				(type default)
			)
			(layer "B.Fab")
		)
		(fp_line
			(start -0.67945 0.3048)
			(end -0.120396 0.3048)
			(stroke
				(width 0.1)
				(type default)
			)
			(layer "B.Fab")
		)
		(fp_line
			(start -0.12065 -0.3048)
			(end -0.67945 -0.3048)
			(stroke
				(width 0.1)
				(type default)
			)
			(layer "B.Fab")
		)
		(fp_line
			(start -0.12065 -0.2794)
			(end -0.12065 -0.3048)
			(stroke
				(width 0.1)
				(type default)
			)
			(layer "B.Fab")
		)
		(fp_line
			(start -0.120396 0.2794)
			(end 0.12065 0.2794)
			(stroke
				(width 0.1)
				(type default)
			)
			(layer "B.Fab")
		)
		(fp_line
			(start -0.120396 0.3048)
			(end -0.120396 0.2794)
			(stroke
				(width 0.1)
				(type default)
			)
			(layer "B.Fab")
		)
		(fp_line
			(start 0.12065 -0.305054)
			(end 0.12065 -0.2794)
			(stroke
				(width 0.1)
				(type default)
			)
			(layer "B.Fab")
		)
		(fp_line
			(start 0.12065 -0.2794)
			(end -0.12065 -0.2794)
			(stroke
				(width 0.1)
				(type default)
			)
			(layer "B.Fab")
		)
		(fp_line
			(start 0.12065 0.2794)
			(end 0.12065 0.3048)
			(stroke
				(width 0.1)
				(type default)
			)
			(layer "B.Fab")
		)
		(fp_line
			(start 0.12065 0.3048)
			(end 0.67945 0.3048)
			(stroke
				(width 0.1)
				(type default)
			)
			(layer "B.Fab")
		)
		(fp_line
			(start 0.67945 -0.305054)
			(end 0.12065 -0.305054)
			(stroke
				(width 0.1)
				(type default)
			)
			(layer "B.Fab")
		)
		(fp_line
			(start 0.67945 0.3048)
			(end 0.67945 -0.305054)
			(stroke
				(width 0.1)
				(type default)
			)
			(layer "B.Fab")
		)
		(pad "1" smd circle
			(at 0.40005 0 180)
			(size 0 0)
			(layers "B.Cu" "B.Mask" "B.Paste")
			(net "P3V3_AUX")
		)
		(pad "2" smd circle
			(at -0.40005 0 180)
			(size 0 0)
			(layers "B.Cu" "B.Mask" "B.Paste")
			(net "FM_PS_PWROK_DLY_R_SEL")
		)
	)
)
